(kicad_pcb
	(version 20260206)
	(generator "pcbnew")
	(generator_version "10.0")
	(general
		(thickness 1.6)
		(legacy_teardrops no)
	)
	(paper "A4")
	(title_block
		(title "01162023_DA0F0TEBIF0_F0T_Expander_BD_F_brd_V02_OCP.brd")
		(comment 1 "Grand Teton / footprints 7024-7030 of 9728")
	)
	(layers
		(0 "F.Cu" signal "TOP")
		(4 "In1.Cu" signal "GND")
		(6 "In2.Cu" signal "VCC")
		(8 "In3.Cu" signal "VCC1")
		(10 "In4.Cu" signal "GND1")
		(12 "In5.Cu" signal "IN1")
		(14 "In6.Cu" signal "GND2")
		(16 "In7.Cu" signal "IN2")
		(18 "In8.Cu" signal "GND3")
		(20 "In9.Cu" signal "IN3")
		(22 "In10.Cu" signal "GND4")
		(24 "In11.Cu" signal "IN4")
		(26 "In12.Cu" signal "GND5")
		(28 "In13.Cu" signal "IN5")
		(30 "In14.Cu" signal "GND6")
		(32 "In15.Cu" signal "IN6")
		(34 "In16.Cu" signal "GND7")
		(2 "B.Cu" signal "BOTTOM")
		(9 "F.Adhes" user "F.Adhesive")
		(11 "B.Adhes" user "B.Adhesive")
		(13 "F.Paste" user "Package Geometry/Pastemask Top")
		(15 "B.Paste" user "Package Geometry/Pastemask Bottom")
		(5 "F.SilkS" user "Ref Des/Silkscreen Top")
		(7 "B.SilkS" user "Ref Des/Silkscreen Bottom")
		(1 "F.Mask" user "Board Geometry/Soldermask Top")
		(3 "B.Mask" user "Board Geometry/Soldermask Bottom")
		(17 "Dwgs.User" user "User.Drawings")
		(19 "Cmts.User" user "User.Comments")
		(21 "Eco1.User" user "User.Eco1")
		(23 "Eco2.User" user "User.Eco2")
		(25 "Edge.Cuts" user "Board Geometry/Outline")
		(27 "Margin" user)
		(31 "F.CrtYd" user "Package Geometry/Place Bound Top")
		(29 "B.CrtYd" user "Package Geometry/Place Bound Bottom")
		(35 "F.Fab" user "Ref Des/Assembly Top")
		(33 "B.Fab" user "Ref Des/Assembly Bottom")
	)
	(footprint ""
		(layer "F.Cu")
		(at 414.197292 -183.078882)
		(property "Reference" "Q239"
			(at -3.857244 -1.611122 0)
			(unlocked yes)
			(layer "F.SilkS")
			(effects
				(font
					(size 0.7874 0.5842)
					(thickness 0.1524)
				)
			)
		)
		(property "Value" ""
			(at 0 0 0)
			(layer "F.Fab")
			(effects
				(font
					(size 1.27 1.27)
				)
			)
		)
		(duplicate_pad_numbers_are_jumpers no)
		(fp_line
			(start -1.376172 -1.199896)
			(end -0.508 -1.199896)
			(stroke
				(width 0.1524)
				(type default)
			)
			(layer "F.SilkS")
		)
		(fp_line
			(start -1.376172 1.199896)
			(end -1.376172 -1.199896)
			(stroke
				(width 0.1524)
				(type default)
			)
			(layer "F.SilkS")
		)
		(fp_line
			(start -0.508 -1.199896)
			(end 0 -0.762)
			(stroke
				(width 0.1524)
				(type default)
			)
			(layer "F.SilkS")
		)
		(fp_line
			(start 0 -0.762)
			(end 0.508 -1.199896)
			(stroke
				(width 0.1524)
				(type default)
			)
			(layer "F.SilkS")
		)
		(fp_line
			(start 0.508 -1.199896)
			(end 1.376172 -1.199896)
			(stroke
				(width 0.1524)
				(type default)
			)
			(layer "F.SilkS")
		)
		(fp_line
			(start 1.376172 -1.199896)
			(end 1.376172 1.199896)
			(stroke
				(width 0.1524)
				(type default)
			)
			(layer "F.SilkS")
		)
		(fp_line
			(start 1.376172 1.199896)
			(end -1.376172 1.199896)
			(stroke
				(width 0.1524)
				(type default)
			)
			(layer "F.SilkS")
		)
		(fp_poly
			(pts
				(xy -1.4605 -0.7493) (xy -2.2225 -1.1303) (xy -2.2225 -0.3683)
			)
			(stroke
				(width 0)
				(type default)
			)
			(fill yes)
			(layer "F.SilkS")
		)
		(fp_line
			(start -0.674878 -1.100074)
			(end 0.674878 -1.100074)
			(stroke
				(width 0.1)
				(type default)
			)
			(layer "F.Fab")
		)
		(fp_line
			(start -0.674878 1.100074)
			(end -0.674878 -1.100074)
			(stroke
				(width 0.1)
				(type default)
			)
			(layer "F.Fab")
		)
		(fp_line
			(start 0.674878 -1.100074)
			(end 0.674878 1.100074)
			(stroke
				(width 0.1)
				(type default)
			)
			(layer "F.Fab")
		)
		(fp_line
			(start 0.674878 1.100074)
			(end -0.674878 1.100074)
			(stroke
				(width 0.1)
				(type default)
			)
			(layer "F.Fab")
		)
		(fp_poly
			(pts
				(xy -1.4605 -0.7493) (xy -2.2225 -1.1303) (xy -2.2225 -0.3683)
			)
			(stroke
				(width 0)
				(type default)
			)
			(fill yes)
			(layer "F.Fab")
		)
		(pad "1" smd rect
			(at -0.899922 -0.750062 270)
			(size 0.6096 0.6096)
			(layers "F.Cu" "F.Mask" "F.Paste")
			(net "GND")
		)
		(pad "2" smd rect
			(at -0.899922 0 270)
			(size 0.4064 0.6096)
			(layers "F.Cu" "F.Mask" "F.Paste")
			(net "FPGA_PEX3_MODE_SEL2_R")
		)
		(pad "3" smd rect
			(at -0.899922 0.750062 270)
			(size 0.6096 0.6096)
			(layers "F.Cu" "F.Mask" "F.Paste")
			(net "FPGA_PEX3_MODE_SEL2_ISO")
		)
		(pad "4" smd rect
			(at 0.899922 0.750062 270)
			(size 0.6096 0.6096)
			(layers "F.Cu" "F.Mask" "F.Paste")
			(net "GND")
		)
		(pad "5" smd rect
			(at 0.899922 0 270)
			(size 0.4064 0.6096)
			(layers "F.Cu" "F.Mask" "F.Paste")
			(net "FPGA_PEX3_MODE_SEL2_D_N")
		)
		(pad "6" smd rect
			(at 0.899922 -0.750062 270)
			(size 0.6096 0.6096)
			(layers "F.Cu" "F.Mask" "F.Paste")
			(net "FPGA_PEX3_MODE_SEL2_D_N")
		)
	)
	(footprint ""
		(layer "F.Cu")
		(at 212.44687 -218.945968 -90)
		(property "Reference" "R4875"
			(at 0 0 270)
			(layer "F.SilkS")
			(hide yes)
			(effects
				(font
					(size 1.27 1.27)
				)
			)
		)
		(property "Value" ""
			(at 0 0 270)
			(layer "F.Fab")
			(effects
				(font
					(size 1.27 1.27)
				)
			)
		)
		(duplicate_pad_numbers_are_jumpers no)
		(fp_line
			(start -0.7874 0.4064)
			(end -0.7874 -0.4064)
			(stroke
				(width 0.1524)
				(type default)
			)
			(layer "F.SilkS")
		)
		(fp_line
			(start 0.7874 0.4064)
			(end -0.7874 0.4064)
			(stroke
				(width 0.1524)
				(type default)
			)
			(layer "F.SilkS")
		)
		(fp_line
			(start -0.7874 -0.4064)
			(end 0.7874 -0.4064)
			(stroke
				(width 0.1524)
				(type default)
			)
			(layer "F.SilkS")
		)
		(fp_line
			(start 0.7874 -0.4064)
			(end 0.7874 0.4064)
			(stroke
				(width 0.1524)
				(type default)
			)
			(layer "F.SilkS")
		)
		(fp_line
			(start -0.67945 0.3048)
			(end -0.67945 -0.305054)
			(stroke
				(width 0.1)
				(type default)
			)
			(layer "F.Fab")
		)
		(fp_line
			(start -0.12065 0.3048)
			(end -0.67945 0.3048)
			(stroke
				(width 0.1)
				(type default)
			)
			(layer "F.Fab")
		)
		(fp_line
			(start 0.120396 0.3048)
			(end 0.120396 0.2794)
			(stroke
				(width 0.1)
				(type default)
			)
			(layer "F.Fab")
		)
		(fp_line
			(start 0.67945 0.3048)
			(end 0.120396 0.3048)
			(stroke
				(width 0.1)
				(type default)
			)
			(layer "F.Fab")
		)
		(fp_line
			(start -0.12065 0.2794)
			(end -0.12065 0.3048)
			(stroke
				(width 0.1)
				(type default)
			)
			(layer "F.Fab")
		)
		(fp_line
			(start 0.120396 0.2794)
			(end -0.12065 0.2794)
			(stroke
				(width 0.1)
				(type default)
			)
			(layer "F.Fab")
		)
		(fp_line
			(start -0.12065 -0.2794)
			(end 0.12065 -0.2794)
			(stroke
				(width 0.1)
				(type default)
			)
			(layer "F.Fab")
		)
		(fp_line
			(start 0.12065 -0.2794)
			(end 0.12065 -0.3048)
			(stroke
				(width 0.1)
				(type default)
			)
			(layer "F.Fab")
		)
		(fp_line
			(start 0.12065 -0.3048)
			(end 0.67945 -0.3048)
			(stroke
				(width 0.1)
				(type default)
			)
			(layer "F.Fab")
		)
		(fp_line
			(start 0.67945 -0.3048)
			(end 0.67945 0.3048)
			(stroke
				(width 0.1)
				(type default)
			)
			(layer "F.Fab")
		)
		(fp_line
			(start -0.67945 -0.305054)
			(end -0.12065 -0.305054)
			(stroke
				(width 0.1)
				(type default)
			)
			(layer "F.Fab")
		)
		(fp_line
			(start -0.12065 -0.305054)
			(end -0.12065 -0.2794)
			(stroke
				(width 0.1)
				(type default)
			)
			(layer "F.Fab")
		)
		(pad "1" smd circle
			(at -0.40005 0 270)
			(size 0 0)
			(layers "F.Cu" "F.Mask" "F.Paste")
			(net "P1V2_AUX")
		)
		(pad "2" smd circle
			(at 0.40005 0 270)
			(size 0 0)
			(layers "F.Cu" "F.Mask" "F.Paste")
			(net "SMB_NIC5_SCL")
		)
	)
	(footprint ""
		(layer "F.Cu")
		(at 36.638484 -130.408934)
		(property "Reference" "C39"
			(at 0 0 0)
			(layer "F.SilkS")
			(hide yes)
			(effects
				(font
					(size 1.27 1.27)
				)
			)
		)
		(property "Value" ""
			(at 0 0 0)
			(layer "F.Fab")
			(effects
				(font
					(size 1.27 1.27)
				)
			)
		)
		(duplicate_pad_numbers_are_jumpers no)
		(fp_line
			(start -0.299974 -0.150114)
			(end 0.299974 -0.150114)
			(stroke
				(width 0.1)
				(type default)
			)
			(layer "F.Fab")
		)
		(fp_line
			(start -0.299974 0.150114)
			(end -0.299974 -0.150114)
			(stroke
				(width 0.1)
				(type default)
			)
			(layer "F.Fab")
		)
		(fp_line
			(start 0.299974 -0.150114)
			(end 0.299974 0.150114)
			(stroke
				(width 0.1)
				(type default)
			)
			(layer "F.Fab")
		)
		(fp_line
			(start 0.299974 0.150114)
			(end -0.299974 0.150114)
			(stroke
				(width 0.1)
				(type default)
			)
			(layer "F.Fab")
		)
		(pad "1" smd rect
			(at -0.2667 0)
			(size 0.3048 0.381)
			(layers "F.Cu" "F.Mask" "F.Paste")
			(net "P5E_PEX0_STN1_TX_DP<28>")
		)
		(pad "2" smd rect
			(at 0.2667 0)
			(size 0.3048 0.381)
			(layers "F.Cu" "F.Mask" "F.Paste")
			(net "P5E_PEX0_STN1_TX_C_DP<28>")
		)
	)
	(footprint ""
		(layer "F.Cu")
		(at 269.25397 -147.969224 90)
		(property "Reference" "C905"
			(at 0 0 90)
			(layer "F.SilkS")
			(hide yes)
			(effects
				(font
					(size 1.27 1.27)
				)
			)
		)
		(property "Value" ""
			(at 0 0 90)
			(layer "F.Fab")
			(effects
				(font
					(size 1.27 1.27)
				)
			)
		)
		(duplicate_pad_numbers_are_jumpers no)
		(fp_line
			(start 1.524 -0.762)
			(end 1.524 0.762)
			(stroke
				(width 0.1524)
				(type default)
			)
			(layer "F.SilkS")
		)
		(fp_line
			(start -1.524 -0.762)
			(end 1.524 -0.762)
			(stroke
				(width 0.1524)
				(type default)
			)
			(layer "F.SilkS")
		)
		(fp_line
			(start 1.524 0.762)
			(end -1.524 0.762)
			(stroke
				(width 0.1524)
				(type default)
			)
			(layer "F.SilkS")
		)
		(fp_line
			(start -1.524 0.762)
			(end -1.524 -0.762)
			(stroke
				(width 0.1524)
				(type default)
			)
			(layer "F.SilkS")
		)
		(fp_line
			(start 1.1049 -0.724916)
			(end -1.1049 -0.724916)
			(stroke
				(width 0.1)
				(type default)
			)
			(layer "F.Fab")
		)
		(fp_line
			(start -1.1049 -0.724916)
			(end -1.1049 0.724916)
			(stroke
				(width 0.1)
				(type default)
			)
			(layer "F.Fab")
		)
		(fp_line
			(start 1.1049 0.724916)
			(end 1.1049 -0.724916)
			(stroke
				(width 0.1)
				(type default)
			)
			(layer "F.Fab")
		)
		(fp_line
			(start -1.1049 0.724916)
			(end 1.1049 0.724916)
			(stroke
				(width 0.1)
				(type default)
			)
			(layer "F.Fab")
		)
		(pad "1" smd rect
			(at -0.889 0 270)
			(size 1.016 1.27)
			(layers "F.Cu" "F.Mask" "F.Paste")
			(net "P12V_NIC4")
		)
		(pad "2" smd rect
			(at 0.889 0 270)
			(size 1.016 1.27)
			(layers "F.Cu" "F.Mask" "F.Paste")
			(net "GND")
		)
	)
	(footprint ""
		(layer "F.Cu")
		(at 323.917818 -224.659698 180)
		(property "Reference" "R2979"
			(at 0 0 180)
			(layer "F.SilkS")
			(hide yes)
			(effects
				(font
					(size 1.27 1.27)
				)
			)
		)
		(property "Value" ""
			(at 0 0 180)
			(layer "F.Fab")
			(effects
				(font
					(size 1.27 1.27)
				)
			)
		)
		(duplicate_pad_numbers_are_jumpers no)
		(fp_line
			(start 0.7874 0.4064)
			(end -0.7874 0.4064)
			(stroke
				(width 0.1524)
				(type default)
			)
			(layer "F.SilkS")
		)
		(fp_line
			(start 0.7874 -0.4064)
			(end 0.7874 0.4064)
			(stroke
				(width 0.1524)
				(type default)
			)
			(layer "F.SilkS")
		)
		(fp_line
			(start -0.7874 0.4064)
			(end -0.7874 -0.4064)
			(stroke
				(width 0.1524)
				(type default)
			)
			(layer "F.SilkS")
		)
		(fp_line
			(start -0.7874 -0.4064)
			(end 0.7874 -0.4064)
			(stroke
				(width 0.1524)
				(type default)
			)
			(layer "F.SilkS")
		)
		(fp_line
			(start 0.67945 0.3048)
			(end 0.120396 0.3048)
			(stroke
				(width 0.1)
				(type default)
			)
			(layer "F.Fab")
		)
		(fp_line
			(start 0.67945 -0.3048)
			(end 0.67945 0.3048)
			(stroke
				(width 0.1)
				(type default)
			)
			(layer "F.Fab")
		)
		(fp_line
			(start 0.12065 -0.2794)
			(end 0.12065 -0.3048)
			(stroke
				(width 0.1)
				(type default)
			)
			(layer "F.Fab")
		)
		(fp_line
			(start 0.12065 -0.3048)
			(end 0.67945 -0.3048)
			(stroke
				(width 0.1)
				(type default)
			)
			(layer "F.Fab")
		)
		(fp_line
			(start 0.120396 0.3048)
			(end 0.120396 0.2794)
			(stroke
				(width 0.1)
				(type default)
			)
			(layer "F.Fab")
		)
		(fp_line
			(start 0.120396 0.2794)
			(end -0.12065 0.2794)
			(stroke
				(width 0.1)
				(type default)
			)
			(layer "F.Fab")
		)
		(fp_line
			(start -0.12065 0.3048)
			(end -0.67945 0.3048)
			(stroke
				(width 0.1)
				(type default)
			)
			(layer "F.Fab")
		)
		(fp_line
			(start -0.12065 0.2794)
			(end -0.12065 0.3048)
			(stroke
				(width 0.1)
				(type default)
			)
			(layer "F.Fab")
		)
		(fp_line
			(start -0.12065 -0.2794)
			(end 0.12065 -0.2794)
			(stroke
				(width 0.1)
				(type default)
			)
			(layer "F.Fab")
		)
		(fp_line
			(start -0.12065 -0.305054)
			(end -0.12065 -0.2794)
			(stroke
				(width 0.1)
				(type default)
			)
			(layer "F.Fab")
		)
		(fp_line
			(start -0.67945 0.3048)
			(end -0.67945 -0.305054)
			(stroke
				(width 0.1)
				(type default)
			)
			(layer "F.Fab")
		)
		(fp_line
			(start -0.67945 -0.305054)
			(end -0.12065 -0.305054)
			(stroke
				(width 0.1)
				(type default)
			)
			(layer "F.Fab")
		)
		(pad "1" smd circle
			(at -0.40005 0 180)
			(size 0 0)
			(layers "F.Cu" "F.Mask" "F.Paste")
			(net "LED_POSTCODE_1")
		)
		(pad "2" smd circle
			(at 0.40005 0 180)
			(size 0 0)
			(layers "F.Cu" "F.Mask" "F.Paste")
			(net "LED_POSTCODE_R_1")
		)
	)
	(footprint ""
		(layer "F.Cu")
		(at 56.373776 -27.006296 -90)
		(property "Reference" "PC684"
			(at 0 0 270)
			(layer "F.SilkS")
			(hide yes)
			(effects
				(font
					(size 1.27 1.27)
				)
			)
		)
		(property "Value" ""
			(at 0 0 270)
			(layer "F.Fab")
			(effects
				(font
					(size 1.27 1.27)
				)
			)
		)
		(duplicate_pad_numbers_are_jumpers no)
		(fp_line
			(start -0.7874 0.4064)
			(end -0.7874 -0.4064)
			(stroke
				(width 0.1524)
				(type default)
			)
			(layer "F.SilkS")
		)
		(fp_line
			(start 0.7874 0.4064)
			(end -0.7874 0.4064)
			(stroke
				(width 0.1524)
				(type default)
			)
			(layer "F.SilkS")
		)
		(fp_line
			(start -0.7874 -0.4064)
			(end 0.7874 -0.4064)
			(stroke
				(width 0.1524)
				(type default)
			)
			(layer "F.SilkS")
		)
		(fp_line
			(start 0.7874 -0.4064)
			(end 0.7874 0.4064)
			(stroke
				(width 0.1524)
				(type default)
			)
			(layer "F.SilkS")
		)
		(fp_line
			(start -0.67945 0.3048)
			(end -0.67945 -0.305054)
			(stroke
				(width 0.1)
				(type default)
			)
			(layer "F.Fab")
		)
		(fp_line
			(start -0.12065 0.3048)
			(end -0.67945 0.3048)
			(stroke
				(width 0.1)
				(type default)
			)
			(layer "F.Fab")
		)
		(fp_line
			(start 0.120396 0.3048)
			(end 0.120396 0.2794)
			(stroke
				(width 0.1)
				(type default)
			)
			(layer "F.Fab")
		)
		(fp_line
			(start 0.67945 0.3048)
			(end 0.120396 0.3048)
			(stroke
				(width 0.1)
				(type default)
			)
			(layer "F.Fab")
		)
		(fp_line
			(start -0.12065 0.2794)
			(end -0.12065 0.3048)
			(stroke
				(width 0.1)
				(type default)
			)
			(layer "F.Fab")
		)
		(fp_line
			(start 0.120396 0.2794)
			(end -0.12065 0.2794)
			(stroke
				(width 0.1)
				(type default)
			)
			(layer "F.Fab")
		)
		(fp_line
			(start -0.12065 -0.2794)
			(end 0.12065 -0.2794)
			(stroke
				(width 0.1)
				(type default)
			)
			(layer "F.Fab")
		)
		(fp_line
			(start 0.12065 -0.2794)
			(end 0.12065 -0.3048)
			(stroke
				(width 0.1)
				(type default)
			)
			(layer "F.Fab")
		)
		(fp_line
			(start 0.12065 -0.3048)
			(end 0.67945 -0.3048)
			(stroke
				(width 0.1)
				(type default)
			)
			(layer "F.Fab")
		)
		(fp_line
			(start 0.67945 -0.3048)
			(end 0.67945 0.3048)
			(stroke
				(width 0.1)
				(type default)
			)
			(layer "F.Fab")
		)
		(fp_line
			(start -0.67945 -0.305054)
			(end -0.12065 -0.305054)
			(stroke
				(width 0.1)
				(type default)
			)
			(layer "F.Fab")
		)
		(fp_line
			(start -0.12065 -0.305054)
			(end -0.12065 -0.2794)
			(stroke
				(width 0.1)
				(type default)
			)
			(layer "F.Fab")
		)
		(pad "1" smd circle
			(at -0.40005 0 270)
			(size 0 0)
			(layers "F.Cu" "F.Mask" "F.Paste")
			(net "P3V3_SSD2_CO_MODE")
		)
		(pad "2" smd circle
			(at 0.40005 0 270)
			(size 0 0)
			(layers "F.Cu" "F.Mask" "F.Paste")
			(net "GND")
		)
	)
	(footprint ""
		(layer "F.Cu")
		(at 115.600226 -119.077486)
		(property "Reference" "R5824"
			(at 0 0 0)
			(layer "F.SilkS")
			(hide yes)
			(effects
				(font
					(size 1.27 1.27)
				)
			)
		)
		(property "Value" ""
			(at 0 0 0)
			(layer "F.Fab")
			(effects
				(font
					(size 1.27 1.27)
				)
			)
		)
		(duplicate_pad_numbers_are_jumpers no)
		(fp_line
			(start -0.7874 -0.4064)
			(end 0.7874 -0.4064)
			(stroke
				(width 0.1524)
				(type default)
			)
			(layer "F.SilkS")
		)
		(fp_line
			(start -0.7874 0.4064)
			(end -0.7874 -0.4064)
			(stroke
				(width 0.1524)
				(type default)
			)
			(layer "F.SilkS")
		)
		(fp_line
			(start 0.7874 -0.4064)
			(end 0.7874 0.4064)
			(stroke
				(width 0.1524)
				(type default)
			)
			(layer "F.SilkS")
		)
		(fp_line
			(start 0.7874 0.4064)
			(end -0.7874 0.4064)
			(stroke
				(width 0.1524)
				(type default)
			)
			(layer "F.SilkS")
		)
		(fp_line
			(start -0.67945 -0.305054)
			(end -0.12065 -0.305054)
			(stroke
				(width 0.1)
				(type default)
			)
			(layer "F.Fab")
		)
		(fp_line
			(start -0.67945 0.3048)
			(end -0.67945 -0.305054)
			(stroke
				(width 0.1)
				(type default)
			)
			(layer "F.Fab")
		)
		(fp_line
			(start -0.12065 -0.305054)
			(end -0.12065 -0.2794)
			(stroke
				(width 0.1)
				(type default)
			)
			(layer "F.Fab")
		)
		(fp_line
			(start -0.12065 -0.2794)
			(end 0.12065 -0.2794)
			(stroke
				(width 0.1)
				(type default)
			)
			(layer "F.Fab")
		)
		(fp_line
			(start -0.12065 0.2794)
			(end -0.12065 0.3048)
			(stroke
				(width 0.1)
				(type default)
			)
			(layer "F.Fab")
		)
		(fp_line
			(start -0.12065 0.3048)
			(end -0.67945 0.3048)
			(stroke
				(width 0.1)
				(type default)
			)
			(layer "F.Fab")
		)
		(fp_line
			(start 0.120396 0.2794)
			(end -0.12065 0.2794)
			(stroke
				(width 0.1)
				(type default)
			)
			(layer "F.Fab")
		)
		(fp_line
			(start 0.120396 0.3048)
			(end 0.120396 0.2794)
			(stroke
				(width 0.1)
				(type default)
			)
			(layer "F.Fab")
		)
		(fp_line
			(start 0.12065 -0.3048)
			(end 0.67945 -0.3048)
			(stroke
				(width 0.1)
				(type default)
			)
			(layer "F.Fab")
		)
		(fp_line
			(start 0.12065 -0.2794)
			(end 0.12065 -0.3048)
			(stroke
				(width 0.1)
				(type default)
			)
			(layer "F.Fab")
		)
		(fp_line
			(start 0.67945 -0.3048)
			(end 0.67945 0.3048)
			(stroke
				(width 0.1)
				(type default)
			)
			(layer "F.Fab")
		)
		(fp_line
			(start 0.67945 0.3048)
			(end 0.120396 0.3048)
			(stroke
				(width 0.1)
				(type default)
			)
			(layer "F.Fab")
		)
		(pad "1" smd circle
			(at -0.40005 0)
			(size 0 0)
			(layers "F.Cu" "F.Mask" "F.Paste")
			(net "PWR_EN_P3V3_R")
		)
		(pad "2" smd circle
			(at 0.40005 0)
			(size 0 0)
			(layers "F.Cu" "F.Mask" "F.Paste")
			(net "P3V3_CO_EN")
		)
	)
)
